# T6G (Grand Teton) — schematic netlist excerpt (pin names and nets, part order shuffled) for the footprints in the layout excerpt that follows; sources: Cadence DE-HDL packaged netlist, KiCad conversion of 04192023_DAF0TMB3IC0_F0TG_MB_C_brd_V02_OCP.brd

R956  Q_RES  0 5% CHIP  pkg 0402LF  page 133 : A = RST_PERST_OCP_SFF_BUF2_N ; B = RST_PERST3_OCP_SFF_N
PC257  Q_CAP  2.2UF 10V 10% X6S  pkg C0402  page 211 : A = PVDDCR_CPU0_P1_VCC2 ; B = GND

(kicad_pcb
	(version 20260206)
	(generator "pcbnew")
	(generator_version "10.0")
	(general
		(thickness 1.6)
		(legacy_teardrops no)
	)
	(paper "A4")
	(title_block
		(title "04192023_DAF0TMB3IC0_F0TG_MB_C_brd_V02_OCP.brd")
		(comment 1 "Grand Teton / footprints 3700-3701 of 8354")
	)
	(layers
		(0 "F.Cu" signal "TOP")
		(4 "In1.Cu" signal "GND")
		(6 "In2.Cu" signal "IN1")
		(8 "In3.Cu" signal "GND1")
		(10 "In4.Cu" signal "IN2")
		(12 "In5.Cu" signal "GND2")
		(14 "In6.Cu" signal "IN3")
		(16 "In7.Cu" signal "GND3")
		(18 "In8.Cu" signal "VCC")
		(20 "In9.Cu" signal "VCC1")
		(22 "In10.Cu" signal "GND4")
		(24 "In11.Cu" signal "IN4")
		(26 "In12.Cu" signal "GND5")
		(28 "In13.Cu" signal "IN5")
		(30 "In14.Cu" signal "GND6")
		(32 "In15.Cu" signal "IN6")
		(34 "In16.Cu" signal "GND7")
		(2 "B.Cu" signal "BOTTOM")
		(9 "F.Adhes" user "F.Adhesive")
		(11 "B.Adhes" user "B.Adhesive")
		(13 "F.Paste" user "Package Geometry/Pastemask Top")
		(15 "B.Paste" user "Package Geometry/Pastemask Bottom")
		(5 "F.SilkS" user "Ref Des/Silkscreen Top")
		(7 "B.SilkS" user "Ref Des/Silkscreen Bottom")
		(1 "F.Mask" user "Board Geometry/Soldermask Top")
		(3 "B.Mask" user "Board Geometry/Soldermask Bottom")
		(17 "Dwgs.User" user "User.Drawings")
		(19 "Cmts.User" user "User.Comments")
		(21 "Eco1.User" user "User.Eco1")
		(23 "Eco2.User" user "User.Eco2")
		(25 "Edge.Cuts" user "Board Geometry/Outline")
		(27 "Margin" user)
		(31 "F.CrtYd" user "Package Geometry/Place Bound Top")
		(29 "B.CrtYd" user "Package Geometry/Place Bound Bottom")
		(35 "F.Fab" user "Ref Des/Assembly Top")
		(33 "B.Fab" user "Ref Des/Assembly Bottom")
	)
	(footprint ""
		(layer "F.Cu")
		(at 94.36481 -180.010562 -90)
		(property "Reference" "PC257"
			(at 0 0 270)
			(layer "F.SilkS")
			(hide yes)
			(effects
				(font
					(size 1.27 1.27)
				)
			)
		)
		(property "Value" ""
			(at 0 0 270)
			(layer "F.Fab")
			(effects
				(font
					(size 1.27 1.27)
				)
			)
		)
		(duplicate_pad_numbers_are_jumpers no)
		(fp_line
			(start -0.7874 0.4064)
			(end -0.7874 -0.4064)
			(stroke
				(width 0.1524)
				(type default)
			)
			(layer "F.SilkS")
		)
		(fp_line
			(start -0.278638 0.4064)
			(end -0.7874 0.4064)
			(stroke
				(width 0.1524)
				(type default)
			)
			(layer "F.SilkS")
		)
		(fp_line
			(start 0.7874 0.4064)
			(end 0.305562 0.4064)
			(stroke
				(width 0.1524)
				(type default)
			)
			(layer "F.SilkS")
		)
		(fp_line
			(start -0.7874 -0.4064)
			(end 0.7874 -0.4064)
			(stroke
				(width 0.1524)
				(type default)
			)
			(layer "F.SilkS")
		)
		(fp_line
			(start 0.7874 -0.4064)
			(end 0.7874 0.4064)
			(stroke
				(width 0.1524)
				(type default)
			)
			(layer "F.SilkS")
		)
		(fp_line
			(start -0.67945 0.3048)
			(end -0.67945 -0.305054)
			(stroke
				(width 0.1)
				(type default)
			)
			(layer "F.Fab")
		)
		(fp_line
			(start -0.12065 0.3048)
			(end -0.67945 0.3048)
			(stroke
				(width 0.1)
				(type default)
			)
			(layer "F.Fab")
		)
		(fp_line
			(start 0.120396 0.3048)
			(end 0.120396 0.2794)
			(stroke
				(width 0.1)
				(type default)
			)
			(layer "F.Fab")
		)
		(fp_line
			(start 0.67945 0.3048)
			(end 0.120396 0.3048)
			(stroke
				(width 0.1)
				(type default)
			)
			(layer "F.Fab")
		)
		(fp_line
			(start -0.12065 0.2794)
			(end -0.12065 0.3048)
			(stroke
				(width 0.1)
				(type default)
			)
			(layer "F.Fab")
		)
		(fp_line
			(start 0.120396 0.2794)
			(end -0.12065 0.2794)
			(stroke
				(width 0.1)
				(type default)
			)
			(layer "F.Fab")
		)
		(fp_line
			(start -0.12065 -0.2794)
			(end 0.12065 -0.2794)
			(stroke
				(width 0.1)
				(type default)
			)
			(layer "F.Fab")
		)
		(fp_line
			(start 0.12065 -0.2794)
			(end 0.12065 -0.3048)
			(stroke
				(width 0.1)
				(type default)
			)
			(layer "F.Fab")
		)
		(fp_line
			(start 0.12065 -0.3048)
			(end 0.67945 -0.3048)
			(stroke
				(width 0.1)
				(type default)
			)
			(layer "F.Fab")
		)
		(fp_line
			(start 0.67945 -0.3048)
			(end 0.67945 0.3048)
			(stroke
				(width 0.1)
				(type default)
			)
			(layer "F.Fab")
		)
		(fp_line
			(start -0.67945 -0.305054)
			(end -0.12065 -0.305054)
			(stroke
				(width 0.1)
				(type default)
			)
			(layer "F.Fab")
		)
		(fp_line
			(start -0.12065 -0.305054)
			(end -0.12065 -0.2794)
			(stroke
				(width 0.1)
				(type default)
			)
			(layer "F.Fab")
		)
		(pad "1" smd circle
			(at -0.40005 0 270)
			(size 0 0)
			(layers "F.Cu" "F.Mask" "F.Paste")
			(net "PVDDCR_CPU0_P1_VCC2")
		)
		(pad "2" smd circle
			(at 0.40005 0 270)
			(size 0 0)
			(layers "F.Cu" "F.Mask" "F.Paste")
			(net "GND")
		)
	)
	(footprint ""
		(layer "F.Cu")
		(at 213.9188 -122.460512)
		(property "Reference" "R956"
			(at 0 0 0)
			(layer "F.SilkS")
			(hide yes)
			(effects
				(font
					(size 1.27 1.27)
				)
			)
		)
		(property "Value" ""
			(at 0 0 0)
			(layer "F.Fab")
			(effects
				(font
					(size 1.27 1.27)
				)
			)
		)
		(duplicate_pad_numbers_are_jumpers no)
		(fp_line
			(start -0.7874 -0.4064)
			(end 0.7874 -0.4064)
			(stroke
				(width 0.1524)
				(type default)
			)
			(layer "F.SilkS")
		)
		(fp_line
			(start -0.7874 0.4064)
			(end -0.7874 -0.4064)
			(stroke
				(width 0.1524)
				(type default)
			)
			(layer "F.SilkS")
		)
		(fp_line
			(start 0.7874 -0.4064)
			(end 0.7874 0.4064)
			(stroke
				(width 0.1524)
				(type default)
			)
			(layer "F.SilkS")
		)
		(fp_line
			(start 0.7874 0.4064)
			(end -0.7874 0.4064)
			(stroke
				(width 0.1524)
				(type default)
			)
			(layer "F.SilkS")
		)
		(fp_line
			(start -0.67945 -0.305054)
			(end -0.12065 -0.305054)
			(stroke
				(width 0.1)
				(type default)
			)
			(layer "F.Fab")
		)
		(fp_line
			(start -0.67945 0.3048)
			(end -0.67945 -0.305054)
			(stroke
				(width 0.1)
				(type default)
			)
			(layer "F.Fab")
		)
		(fp_line
			(start -0.12065 -0.305054)
			(end -0.12065 -0.2794)
			(stroke
				(width 0.1)
				(type default)
			)
			(layer "F.Fab")
		)
		(fp_line
			(start -0.12065 -0.2794)
			(end 0.12065 -0.2794)
			(stroke
				(width 0.1)
				(type default)
			)
			(layer "F.Fab")
		)
		(fp_line
			(start -0.12065 0.2794)
			(end -0.12065 0.3048)
			(stroke
				(width 0.1)
				(type default)
			)
			(layer "F.Fab")
		)
		(fp_line
			(start -0.12065 0.3048)
			(end -0.67945 0.3048)
			(stroke
				(width 0.1)
				(type default)
			)
			(layer "F.Fab")
		)
		(fp_line
			(start 0.120396 0.2794)
			(end -0.12065 0.2794)
			(stroke
				(width 0.1)
				(type default)
			)
			(layer "F.Fab")
		)
		(fp_line
			(start 0.120396 0.3048)
			(end 0.120396 0.2794)
			(stroke
				(width 0.1)
				(type default)
			)
			(layer "F.Fab")
		)
		(fp_line
			(start 0.12065 -0.3048)
			(end 0.67945 -0.3048)
			(stroke
				(width 0.1)
				(type default)
			)
			(layer "F.Fab")
		)
		(fp_line
			(start 0.12065 -0.2794)
			(end 0.12065 -0.3048)
			(stroke
				(width 0.1)
				(type default)
			)
			(layer "F.Fab")
		)
		(fp_line
			(start 0.67945 -0.3048)
			(end 0.67945 0.3048)
			(stroke
				(width 0.1)
				(type default)
			)
			(layer "F.Fab")
		)
		(fp_line
			(start 0.67945 0.3048)
			(end 0.120396 0.3048)
			(stroke
				(width 0.1)
				(type default)
			)
			(layer "F.Fab")
		)
		(pad "1" smd circle
			(at -0.40005 0)
			(size 0 0)
			(layers "F.Cu" "F.Mask" "F.Paste")
			(net "RST_PERST_OCP_SFF_BUF2_N")
		)
		(pad "2" smd circle
			(at 0.40005 0)
			(size 0 0)
			(layers "F.Cu" "F.Mask" "F.Paste")
			(net "RST_PERST3_OCP_SFF_N")
		)
	)
)
